(kicad_pcb
	(version 20260206)
	(generator "pcbnew")
	(generator_version "10.0")
	(general
		(thickness 1.6)
		(legacy_teardrops no)
	)
	(paper "A4")
	(title_block
		(title "Bryce Canyon_IOM_IOC_16318-2_OCP.brd")
		(comment 1 "Bryce Canyon / footprints 230-237 of 1605")
	)
	(layers
		(0 "F.Cu" signal "TOP")
		(4 "In1.Cu" signal "L2GND")
		(6 "In2.Cu" signal "L3")
		(8 "In3.Cu" signal "L4VCC")
		(10 "In4.Cu" signal "L5VCC")
		(12 "In5.Cu" signal "L6")
		(14 "In6.Cu" signal "L7GND")
		(2 "B.Cu" signal "BOTTOM")
		(9 "F.Adhes" user "F.Adhesive")
		(11 "B.Adhes" user "B.Adhesive")
		(13 "F.Paste" user "Package Geometry/Pastemask Top")
		(15 "B.Paste" user "Package Geometry/Pastemask Bottom")
		(5 "F.SilkS" user "Ref Des/Silkscreen Top")
		(7 "B.SilkS" user "Ref Des/Silkscreen Bottom")
		(1 "F.Mask" user "Board Geometry/Soldermask Top")
		(3 "B.Mask" user "Board Geometry/Soldermask Bottom")
		(17 "Dwgs.User" user "User.Drawings")
		(19 "Cmts.User" user "User.Comments")
		(21 "Eco1.User" user "User.Eco1")
		(23 "Eco2.User" user "User.Eco2")
		(25 "Edge.Cuts" user "Board Geometry/Outline")
		(27 "Margin" user)
		(31 "F.CrtYd" user "Package Geometry/Place Bound Top")
		(29 "B.CrtYd" user "Package Geometry/Place Bound Bottom")
		(35 "F.Fab" user "Ref Des/Assembly Top")
		(33 "B.Fab" user "Ref Des/Assembly Bottom")
	)
	(footprint ""
		(layer "F.Cu")
		(at 79.11338 -133.677914 90)
		(property "Reference" "U45"
			(at 0 0 90)
			(layer "F.SilkS")
			(hide yes)
			(effects
				(font
					(size 1.27 1.27)
				)
			)
		)
		(property "Value" "PCA9306DCTT-GP"
			(at 0 -11.6332 90)
			(unlocked yes)
			(layer "F.Fab")
			(hide yes)
			(effects
				(font
					(size 1.016 1.016)
					(thickness 0.1524)
				)
			)
		)
		(property "Device Type" "SSOIC8H52"
			(at 0 -13.1572 90)
			(unlocked yes)
			(layer "F.Fab")
			(hide yes)
			(effects
				(font
					(size 1.016 1.016)
					(thickness 0.1524)
				)
			)
		)
		(duplicate_pad_numbers_are_jumpers no)
		(fp_line
			(start 1.0668 -0.5842)
			(end 1.0668 0.5842)
			(stroke
				(width 0.1524)
				(type default)
			)
			(layer "F.SilkS")
		)
		(fp_line
			(start -1.7018 -0.5842)
			(end 1.0668 -0.5842)
			(stroke
				(width 0.1524)
				(type default)
			)
			(layer "F.SilkS")
		)
		(fp_line
			(start -1.7018 -0.5842)
			(end -1.7018 2.286)
			(stroke
				(width 0.1524)
				(type default)
			)
			(layer "F.SilkS")
		)
		(fp_line
			(start -1.397 0)
			(end -1.7018 -0.3048)
			(stroke
				(width 0.1524)
				(type default)
			)
			(layer "F.SilkS")
		)
		(fp_line
			(start -1.397 0)
			(end -1.7018 0.3048)
			(stroke
				(width 0.1524)
				(type default)
			)
			(layer "F.SilkS")
		)
		(fp_line
			(start 1.0668 0.5842)
			(end -1.524 0.5842)
			(stroke
				(width 0.1524)
				(type default)
			)
			(layer "F.SilkS")
		)
		(fp_line
			(start -1.524 0.5842)
			(end -1.524 2.286)
			(stroke
				(width 0.508)
				(type default)
			)
			(layer "F.SilkS")
		)
		(fp_poly
			(pts
				(xy -1.1684 -0.5842) (xy 1.0668 -0.5842) (xy 1.0668 0.5842) (xy -1.1684 0.5842)
			)
			(stroke
				(width 0)
				(type default)
			)
			(fill yes)
			(layer "F.SilkS")
		)
		(fp_poly
			(pts
				(xy -1.778 2.54) (xy 1.778 2.54) (xy 1.778 -2.54) (xy -1.778 -2.54)
			)
			(stroke
				(width 0)
				(type default)
			)
			(fill no)
			(layer "F.CrtYd")
		)
		(fp_poly
			(pts
				(xy -1.778 -2.54) (xy 1.778 -2.54) (xy 1.778 2.54) (xy -1.778 2.54)
			)
			(stroke
				(width 0)
				(type default)
			)
			(fill no)
			(layer "F.Fab")
		)
		(pad "1" smd rect
			(at -0.97536 1.6256 90)
			(size 0.3556 1.524)
			(layers "F.Cu" "F.Mask" "F.Paste")
			(net "GND")
		)
		(pad "2" smd rect
			(at -0.32512 1.6256 90)
			(size 0.3556 1.524)
			(layers "F.Cu" "F.Mask" "F.Paste")
			(net "P3V3_STBY")
		)
		(pad "3" smd rect
			(at 0.32512 1.6256 90)
			(size 0.3556 1.524)
			(layers "F.Cu" "F.Mask" "F.Paste")
			(net "I2C_DEBUG_SCL")
		)
		(pad "4" smd rect
			(at 0.97536 1.6256 90)
			(size 0.3556 1.524)
			(layers "F.Cu" "F.Mask" "F.Paste")
			(net "I2C_DEBUG_SDA")
		)
		(pad "5" smd rect
			(at 0.97536 -1.6256 90)
			(size 0.3556 1.524)
			(layers "F.Cu" "F.Mask" "F.Paste")
			(net "I2C_DEBUG_SDA_L")
		)
		(pad "6" smd rect
			(at 0.32512 -1.6256 90)
			(size 0.3556 1.524)
			(layers "F.Cu" "F.Mask" "F.Paste")
			(net "I2C_DEBUG_SCL_L")
		)
		(pad "7" smd rect
			(at -0.32512 -1.6256 90)
			(size 0.3556 1.524)
			(layers "F.Cu" "F.Mask" "F.Paste")
			(net "P3V3_STBY")
		)
		(pad "8" smd rect
			(at -0.97536 -1.6256 90)
			(size 0.3556 1.524)
			(layers "F.Cu" "F.Mask" "F.Paste")
			(net "DEBUG_CARD_PRSNT")
		)
	)
	(footprint ""
		(layer "F.Cu")
		(at 191.287146 -133.290564)
		(property "Reference" "R556"
			(at 0 0 0)
			(layer "F.SilkS")
			(hide yes)
			(effects
				(font
					(size 1.27 1.27)
				)
			)
		)
		(property "Value" "10KR2F-2-GP"
			(at 0.064008 -3.993896 0)
			(unlocked yes)
			(layer "F.Fab")
			(hide yes)
			(effects
				(font
					(size 1.016 1.016)
					(thickness 0.1524)
				)
			)
		)
		(property "Device Type" "R402H16"
			(at 0.064008 -5.517896 0)
			(unlocked yes)
			(layer "F.Fab")
			(hide yes)
			(effects
				(font
					(size 1.016 1.016)
					(thickness 0.1524)
				)
			)
		)
		(duplicate_pad_numbers_are_jumpers no)
		(fp_line
			(start -0.508 -0.9398)
			(end -0.508 0.9398)
			(stroke
				(width 0.1524)
				(type default)
			)
			(layer "F.SilkS")
		)
		(fp_line
			(start 0.508 -0.9398)
			(end -0.508 -0.9398)
			(stroke
				(width 0.1524)
				(type default)
			)
			(layer "F.SilkS")
		)
		(fp_rect
			(start -0.508 0.9398)
			(end 0.508 -0.9398)
			(stroke
				(width 0)
				(type default)
			)
			(fill no)
			(layer "F.CrtYd")
		)
		(fp_rect
			(start -0.508 0.9398)
			(end 0.508 -0.9398)
			(stroke
				(width 0)
				(type default)
			)
			(fill no)
			(layer "F.Fab")
		)
		(pad "1" smd custom
			(at 0 -0.4445)
			(size 0.1397 0.1397)
			(layers "F.Cu" "F.Mask" "F.Paste")
			(net "P3V3_STBY")
			(options
				(clearance outline)
				(anchor circle)
			)
			(primitives
				(gr_poly
					(pts
						(arc
							(start -0.1778 -0.2794)
							(mid -0.249642 -0.249642)
							(end -0.2794 -0.1778)
						)
						(arc
							(start -0.2794 0.1778)
							(mid -0.249642 0.249642)
							(end -0.1778 0.2794)
						)
						(arc
							(start 0.1778 0.2794)
							(mid 0.249642 0.249642)
							(end 0.2794 0.1778)
						)
						(arc
							(start 0.2794 -0.1778)
							(mid 0.249642 -0.249642)
							(end 0.1778 -0.2794)
						)
					)
					(width 0)
					(fill yes)
				)
			)
		)
		(pad "2" smd custom
			(at 0 0.4445)
			(size 0.1397 0.1397)
			(layers "F.Cu" "F.Mask" "F.Paste")
			(net "VT235_EN")
			(options
				(clearance outline)
				(anchor circle)
			)
			(primitives
				(gr_poly
					(pts
						(arc
							(start -0.1778 -0.2794)
							(mid -0.249642 -0.249642)
							(end -0.2794 -0.1778)
						)
						(arc
							(start -0.2794 0.1778)
							(mid -0.249642 0.249642)
							(end -0.1778 0.2794)
						)
						(arc
							(start 0.1778 0.2794)
							(mid 0.249642 0.249642)
							(end 0.2794 0.1778)
						)
						(arc
							(start 0.2794 -0.1778)
							(mid 0.249642 -0.249642)
							(end 0.1778 -0.2794)
						)
					)
					(width 0)
					(fill yes)
				)
			)
		)
	)
	(footprint ""
		(layer "F.Cu")
		(at 176.8348 -76.6318 90)
		(property "Reference" "TP96"
			(at 0 0 90)
			(layer "F.SilkS")
			(hide yes)
			(effects
				(font
					(size 1.27 1.27)
				)
			)
		)
		(property "Value" "TPAD28-2-GP"
			(at -0.0127 -1.6637 90)
			(unlocked yes)
			(layer "F.Fab")
			(hide yes)
			(effects
				(font
					(size 1.016 1.016)
					(thickness 0.1524)
				)
			)
		)
		(property "Device Type" "TPAD28"
			(at -0.0127 -3.1877 90)
			(unlocked yes)
			(layer "F.Fab")
			(hide yes)
			(effects
				(font
					(size 1.016 1.016)
					(thickness 0.1524)
				)
			)
		)
		(duplicate_pad_numbers_are_jumpers no)
		(fp_poly
			(pts
				(arc
					(start 0 0.3556)
					(mid 0 -0.3556)
					(end 0 0.3556)
				)
			)
			(stroke
				(width 0)
				(type default)
			)
			(fill no)
			(layer "F.CrtYd")
		)
		(fp_poly
			(pts
				(arc
					(start 0 0.6096)
					(mid 0 -0.6096)
					(end 0 0.6096)
				)
			)
			(stroke
				(width 0)
				(type default)
			)
			(fill no)
			(layer "F.Fab")
		)
		(pad "1" smd circle
			(at 0 0 90)
			(size 0.7112 0.7112)
			(layers "F.Cu" "F.Mask" "F.Paste")
			(net "IOC_GPIO_11")
		)
	)
	(footprint ""
		(layer "F.Cu")
		(at 177.2539 -51.70424 90)
		(property "Reference" "R729"
			(at 0 0 90)
			(layer "F.SilkS")
			(hide yes)
			(effects
				(font
					(size 1.27 1.27)
				)
			)
		)
		(property "Value" "10KR2F-2-GP"
			(at 0.064008 -3.993896 90)
			(unlocked yes)
			(layer "F.Fab")
			(hide yes)
			(effects
				(font
					(size 1.016 1.016)
					(thickness 0.1524)
				)
			)
		)
		(property "Device Type" "R402H16"
			(at 0.064008 -5.517896 90)
			(unlocked yes)
			(layer "F.Fab")
			(hide yes)
			(effects
				(font
					(size 1.016 1.016)
					(thickness 0.1524)
				)
			)
		)
		(duplicate_pad_numbers_are_jumpers no)
		(fp_line
			(start 0.508 -0.9398)
			(end -0.508 -0.9398)
			(stroke
				(width 0.1524)
				(type default)
			)
			(layer "F.SilkS")
		)
		(fp_line
			(start -0.508 -0.9398)
			(end -0.508 0.9398)
			(stroke
				(width 0.1524)
				(type default)
			)
			(layer "F.SilkS")
		)
		(fp_rect
			(start -0.508 0.9398)
			(end 0.508 -0.9398)
			(stroke
				(width 0)
				(type default)
			)
			(fill no)
			(layer "F.CrtYd")
		)
		(fp_rect
			(start -0.508 0.9398)
			(end 0.508 -0.9398)
			(stroke
				(width 0)
				(type default)
			)
			(fill no)
			(layer "F.Fab")
		)
		(pad "1" smd custom
			(at 0 -0.4445 90)
			(size 0.1397 0.1397)
			(layers "F.Cu" "F.Mask" "F.Paste")
			(net "P1V8")
			(options
				(clearance outline)
				(anchor circle)
			)
			(primitives
				(gr_poly
					(pts
						(arc
							(start -0.1778 -0.2794)
							(mid -0.249642 -0.249642)
							(end -0.2794 -0.1778)
						)
						(arc
							(start -0.2794 0.1778)
							(mid -0.249642 0.249642)
							(end -0.1778 0.2794)
						)
						(arc
							(start 0.1778 0.2794)
							(mid 0.249642 0.249642)
							(end 0.2794 0.1778)
						)
						(arc
							(start 0.2794 -0.1778)
							(mid 0.249642 -0.249642)
							(end 0.1778 -0.2794)
						)
					)
					(width 0)
					(fill yes)
				)
			)
		)
		(pad "2" smd custom
			(at 0 0.4445 90)
			(size 0.1397 0.1397)
			(layers "F.Cu" "F.Mask" "F.Paste")
			(net "XM_OE_N")
			(options
				(clearance outline)
				(anchor circle)
			)
			(primitives
				(gr_poly
					(pts
						(arc
							(start -0.1778 -0.2794)
							(mid -0.249642 -0.249642)
							(end -0.2794 -0.1778)
						)
						(arc
							(start -0.2794 0.1778)
							(mid -0.249642 0.249642)
							(end -0.1778 0.2794)
						)
						(arc
							(start 0.1778 0.2794)
							(mid 0.249642 0.249642)
							(end 0.2794 0.1778)
						)
						(arc
							(start 0.2794 -0.1778)
							(mid 0.249642 -0.249642)
							(end 0.1778 -0.2794)
						)
					)
					(width 0)
					(fill yes)
				)
			)
		)
	)
	(footprint ""
		(layer "F.Cu")
		(at 157.099 -122.174 -90)
		(property "Reference" "C217"
			(at 0 0 270)
			(layer "F.SilkS")
			(hide yes)
			(effects
				(font
					(size 1.27 1.27)
				)
			)
		)
		(property "Value" "SC10U6D3V5KX-4GP"
			(at -0.0762 -6.1214 270)
			(unlocked yes)
			(layer "F.Fab")
			(hide yes)
			(effects
				(font
					(size 1.016 1.016)
					(thickness 0.1524)
				)
			)
		)
		(property "Device Type" "C805H58"
			(at -0.0762 -8.1534 270)
			(unlocked yes)
			(layer "F.Fab")
			(hide yes)
			(effects
				(font
					(size 1.016 1.016)
					(thickness 0.1524)
				)
			)
		)
		(duplicate_pad_numbers_are_jumpers no)
		(fp_line
			(start 0.635 0)
			(end -0.635 0)
			(stroke
				(width 0.508)
				(type default)
			)
			(layer "F.SilkS")
		)
		(fp_rect
			(start -0.9652 1.778)
			(end 0.9652 -1.778)
			(stroke
				(width 0)
				(type default)
			)
			(fill no)
			(layer "F.CrtYd")
		)
		(fp_poly
			(pts
				(xy -0.9652 -1.778) (xy 0.9652 -1.778) (xy 0.9652 1.778) (xy -0.9652 1.778)
			)
			(stroke
				(width 0)
				(type default)
			)
			(fill no)
			(layer "F.Fab")
		)
		(pad "1" smd rect
			(at 0 -0.9652 270)
			(size 1.397 1.143)
			(layers "F.Cu" "F.Mask" "F.Paste")
			(net "P1V8_STBY")
		)
		(pad "2" smd rect
			(at 0 0.9652 270)
			(size 1.397 1.143)
			(layers "F.Cu" "F.Mask" "F.Paste")
			(net "GND")
		)
	)
	(footprint ""
		(layer "F.Cu")
		(at 182.8546 -146.3802 -90)
		(property "Reference" "G2"
			(at 0 0 270)
			(layer "F.SilkS")
			(hide yes)
			(effects
				(font
					(size 1.27 1.27)
				)
			)
		)
		(property "Value" "COPPER-CLOSE-GP-U"
			(at 0.0762 -2.8702 270)
			(unlocked yes)
			(layer "F.Fab")
			(hide yes)
			(effects
				(font
					(size 1.016 1.016)
					(thickness 0.1524)
				)
			)
		)
		(property "Device Type" "CON2C-U"
			(at 0.0762 -4.3942 270)
			(unlocked yes)
			(layer "F.Fab")
			(hide yes)
			(effects
				(font
					(size 1.016 1.016)
					(thickness 0.1524)
				)
			)
		)
		(duplicate_pad_numbers_are_jumpers no)
		(fp_rect
			(start -0.9398 0.9652)
			(end 0.9398 -0.9652)
			(stroke
				(width 0)
				(type default)
			)
			(fill no)
			(layer "F.CrtYd")
		)
		(fp_rect
			(start -0.9398 0.9652)
			(end 0.9398 -0.9652)
			(stroke
				(width 0)
				(type default)
			)
			(fill no)
			(layer "F.Fab")
		)
		(pad "1" smd custom
			(at 0 -0.5334 270)
			(size 0.17145 0.17145)
			(layers "F.Cu" "F.Mask" "F.Paste")
			(net "AGND_P5V")
			(options
				(clearance outline)
				(anchor circle)
			)
			(primitives
				(gr_poly
					(pts
						(xy -0.127 0.3429) (xy -0.127 0.1651) (xy -0.635 -0.3429) (xy 0.635 -0.3429) (xy 0.127 0.1651)
						(xy 0.127 0.3429)
					)
					(width 0)
					(fill yes)
				)
			)
		)
		(pad "2" smd custom
			(at 0 0.5334 270)
			(size 0.17145 0.17145)
			(layers "F.Cu" "F.Mask" "F.Paste")
			(net "GND")
			(options
				(clearance outline)
				(anchor circle)
			)
			(primitives
				(gr_poly
					(pts
						(xy -0.635 0.3429) (xy -0.127 -0.1651) (xy -0.127 -0.3429) (xy 0.127 -0.3429) (xy 0.127 -0.1651)
						(xy 0.635 0.3429)
					)
					(width 0)
					(fill yes)
				)
			)
		)
	)
	(footprint ""
		(layer "F.Cu")
		(at 208.68132 -84.393786 135)
		(property "Reference" "VIA26"
			(at 0 0 135)
			(layer "F.SilkS")
			(hide yes)
			(effects
				(font
					(size 1.27 1.27)
				)
			)
		)
		(property "Value" "85OHM-8L-1D6MM-L16L18-GP"
			(at 4.063925 0.609475 135)
			(unlocked yes)
			(layer "F.Fab")
			(hide yes)
			(effects
				(font
					(size 1.016 1.016)
					(thickness 0.1524)
				)
			)
		)
		(property "Device Type" "VIA-PCIE-4P-368076"
			(at 4.064105 -0.914474 135)
			(unlocked yes)
			(layer "F.Fab")
			(hide yes)
			(effects
				(font
					(size 1.016 1.016)
					(thickness 0.1524)
				)
			)
		)
		(duplicate_pad_numbers_are_jumpers no)
		(fp_poly
			(pts
				(xy -1.841491 -0.381057) (xy 1.841509 -0.381058) (xy 1.841508 0.380942) (xy -1.841491 0.380942)
			)
			(stroke
				(width 0)
				(type default)
			)
			(fill no)
			(layer "F.CrtYd")
		)
		(fp_poly
			(pts
				(xy -1.841491 -0.381057) (xy 1.841509 -0.381058) (xy 1.841508 0.380942) (xy -1.841491 0.380942)
			)
			(stroke
				(width 0)
				(type default)
			)
			(fill no)
			(layer "F.Fab")
		)
		(pad "1" thru_hole circle
			(at -1.460499 0 135)
			(size 0.508 0.508)
			(drill 0.254)
			(layers "*.Cu" "*.Mask")
			(remove_unused_layers no)
			(net "GND")
			(clearance 0.127)
			(thermal_gap 0.127)
		)
		(pad "2" thru_hole circle
			(at -0.4445 0 135)
			(size 0.508 0.508)
			(drill 0.254)
			(layers "*.Cu" "*.Mask")
			(remove_unused_layers no)
			(net "PCIE_COMP_TO_IOM_CLK_2_DP")
			(clearance 0.127)
			(thermal_gap 0.127)
		)
		(pad "3" thru_hole circle
			(at 0.4445 0 135)
			(size 0.508 0.508)
			(drill 0.254)
			(layers "*.Cu" "*.Mask")
			(remove_unused_layers no)
			(net "PCIE_COMP_TO_IOM_CLK_2_DN")
			(clearance 0.127)
			(thermal_gap 0.127)
		)
		(pad "4" thru_hole circle
			(at 1.460499 0 135)
			(size 0.508 0.508)
			(drill 0.254)
			(layers "*.Cu" "*.Mask")
			(remove_unused_layers no)
			(net "GND")
			(clearance 0.127)
			(thermal_gap 0.127)
		)
	)
	(footprint ""
		(layer "F.Cu")
		(at 34.151062 -154.883358 -90)
		(property "Reference" "R322"
			(at 0 0 270)
			(layer "F.SilkS")
			(hide yes)
			(effects
				(font
					(size 1.27 1.27)
				)
			)
		)
		(property "Value" "0R2J-2-GP"
			(at 0.064008 -3.993896 270)
			(unlocked yes)
			(layer "F.Fab")
			(hide yes)
			(effects
				(font
					(size 1.016 1.016)
					(thickness 0.1524)
				)
			)
		)
		(property "Device Type" "R402H16"
			(at 0.064008 -5.517896 270)
			(unlocked yes)
			(layer "F.Fab")
			(hide yes)
			(effects
				(font
					(size 1.016 1.016)
					(thickness 0.1524)
				)
			)
		)
		(duplicate_pad_numbers_are_jumpers no)
		(fp_line
			(start -0.508 -0.9398)
			(end -0.508 0.9398)
			(stroke
				(width 0.1524)
				(type default)
			)
			(layer "F.SilkS")
		)
		(fp_line
			(start 0.508 -0.9398)
			(end -0.508 -0.9398)
			(stroke
				(width 0.1524)
				(type default)
			)
			(layer "F.SilkS")
		)
		(fp_rect
			(start -0.508 0.9398)
			(end 0.508 -0.9398)
			(stroke
				(width 0)
				(type default)
			)
			(fill no)
			(layer "F.CrtYd")
		)
		(fp_rect
			(start -0.508 0.9398)
			(end 0.508 -0.9398)
			(stroke
				(width 0)
				(type default)
			)
			(fill no)
			(layer "F.Fab")
		)
		(pad "1" smd custom
			(at 0 -0.4445 270)
			(size 0.1397 0.1397)
			(layers "F.Cu" "F.Mask" "F.Paste")
			(net "COMP_POWER_FAIL_R_N")
			(options
				(clearance outline)
				(anchor circle)
			)
			(primitives
				(gr_poly
					(pts
						(arc
							(start -0.1778 -0.2794)
							(mid -0.249642 -0.249642)
							(end -0.2794 -0.1778)
						)
						(arc
							(start -0.2794 0.1778)
							(mid -0.249642 0.249642)
							(end -0.1778 0.2794)
						)
						(arc
							(start 0.1778 0.2794)
							(mid 0.249642 0.249642)
							(end 0.2794 0.1778)
						)
						(arc
							(start 0.2794 -0.1778)
							(mid 0.249642 -0.249642)
							(end 0.1778 -0.2794)
						)
					)
					(width 0)
					(fill yes)
				)
			)
		)
		(pad "2" smd custom
			(at 0 0.4445 270)
			(size 0.1397 0.1397)
			(layers "F.Cu" "F.Mask" "F.Paste")
			(net "COMP_POWER_FAIL_N")
			(options
				(clearance outline)
				(anchor circle)
			)
			(primitives
				(gr_poly
					(pts
						(arc
							(start -0.1778 -0.2794)
							(mid -0.249642 -0.249642)
							(end -0.2794 -0.1778)
						)
						(arc
							(start -0.2794 0.1778)
							(mid -0.249642 0.249642)
							(end -0.1778 0.2794)
						)
						(arc
							(start 0.1778 0.2794)
							(mid 0.249642 0.249642)
							(end 0.2794 0.1778)
						)
						(arc
							(start 0.2794 -0.1778)
							(mid 0.249642 -0.249642)
							(end 0.1778 -0.2794)
						)
					)
					(width 0)
					(fill yes)
				)
			)
		)
	)
)
